(kicad_pcb
	(version 20260206)
	(generator "pcbnew")
	(generator_version "10.0")
	(general
		(thickness 1.6)
		(legacy_teardrops no)
	)
	(paper "A4")
	(title_block
		(title "04192023_DAF0TMB3IC0_F0TG_MB_C_brd_V02_OCP.brd")
		(comment 1 "Grand Teton / footprints 5621-5628 of 8354")
	)
	(layers
		(0 "F.Cu" signal "TOP")
		(4 "In1.Cu" signal "GND")
		(6 "In2.Cu" signal "IN1")
		(8 "In3.Cu" signal "GND1")
		(10 "In4.Cu" signal "IN2")
		(12 "In5.Cu" signal "GND2")
		(14 "In6.Cu" signal "IN3")
		(16 "In7.Cu" signal "GND3")
		(18 "In8.Cu" signal "VCC")
		(20 "In9.Cu" signal "VCC1")
		(22 "In10.Cu" signal "GND4")
		(24 "In11.Cu" signal "IN4")
		(26 "In12.Cu" signal "GND5")
		(28 "In13.Cu" signal "IN5")
		(30 "In14.Cu" signal "GND6")
		(32 "In15.Cu" signal "IN6")
		(34 "In16.Cu" signal "GND7")
		(2 "B.Cu" signal "BOTTOM")
		(9 "F.Adhes" user "F.Adhesive")
		(11 "B.Adhes" user "B.Adhesive")
		(13 "F.Paste" user "Package Geometry/Pastemask Top")
		(15 "B.Paste" user "Package Geometry/Pastemask Bottom")
		(5 "F.SilkS" user "Ref Des/Silkscreen Top")
		(7 "B.SilkS" user "Ref Des/Silkscreen Bottom")
		(1 "F.Mask" user "Board Geometry/Soldermask Top")
		(3 "B.Mask" user "Board Geometry/Soldermask Bottom")
		(17 "Dwgs.User" user "User.Drawings")
		(19 "Cmts.User" user "User.Comments")
		(21 "Eco1.User" user "User.Eco1")
		(23 "Eco2.User" user "User.Eco2")
		(25 "Edge.Cuts" user "Board Geometry/Outline")
		(27 "Margin" user)
		(31 "F.CrtYd" user "Package Geometry/Place Bound Top")
		(29 "B.CrtYd" user "Package Geometry/Place Bound Bottom")
		(35 "F.Fab" user "Ref Des/Assembly Top")
		(33 "B.Fab" user "Ref Des/Assembly Bottom")
	)
	(footprint ""
		(layer "B.Cu")
		(at 156.154374 -323.798692)
		(property "Reference" "R562"
			(at 0 0 0)
			(layer "B.SilkS")
			(hide yes)
			(effects
				(font
					(size 1.27 1.27)
				)
				(justify mirror)
			)
		)
		(property "Value" ""
			(at 0 0 0)
			(layer "B.Fab")
			(effects
				(font
					(size 1.27 1.27)
				)
				(justify mirror)
			)
		)
		(duplicate_pad_numbers_are_jumpers no)
		(fp_line
			(start -0.7874 -0.4064)
			(end -0.7874 0.4064)
			(stroke
				(width 0.1524)
				(type default)
			)
			(layer "B.SilkS")
		)
		(fp_line
			(start -0.7874 0.4064)
			(end 0.7874 0.4064)
			(stroke
				(width 0.1524)
				(type default)
			)
			(layer "B.SilkS")
		)
		(fp_line
			(start 0.7874 -0.4064)
			(end -0.7874 -0.4064)
			(stroke
				(width 0.1524)
				(type default)
			)
			(layer "B.SilkS")
		)
		(fp_line
			(start 0.7874 0.4064)
			(end 0.7874 -0.4064)
			(stroke
				(width 0.1524)
				(type default)
			)
			(layer "B.SilkS")
		)
		(fp_line
			(start -0.67945 -0.3048)
			(end -0.67945 0.3048)
			(stroke
				(width 0.1)
				(type default)
			)
			(layer "B.Fab")
		)
		(fp_line
			(start -0.67945 0.3048)
			(end -0.120396 0.3048)
			(stroke
				(width 0.1)
				(type default)
			)
			(layer "B.Fab")
		)
		(fp_line
			(start -0.12065 -0.3048)
			(end -0.67945 -0.3048)
			(stroke
				(width 0.1)
				(type default)
			)
			(layer "B.Fab")
		)
		(fp_line
			(start -0.12065 -0.2794)
			(end -0.12065 -0.3048)
			(stroke
				(width 0.1)
				(type default)
			)
			(layer "B.Fab")
		)
		(fp_line
			(start -0.120396 0.2794)
			(end 0.12065 0.2794)
			(stroke
				(width 0.1)
				(type default)
			)
			(layer "B.Fab")
		)
		(fp_line
			(start -0.120396 0.3048)
			(end -0.120396 0.2794)
			(stroke
				(width 0.1)
				(type default)
			)
			(layer "B.Fab")
		)
		(fp_line
			(start 0.12065 -0.305054)
			(end 0.12065 -0.2794)
			(stroke
				(width 0.1)
				(type default)
			)
			(layer "B.Fab")
		)
		(fp_line
			(start 0.12065 -0.2794)
			(end -0.12065 -0.2794)
			(stroke
				(width 0.1)
				(type default)
			)
			(layer "B.Fab")
		)
		(fp_line
			(start 0.12065 0.2794)
			(end 0.12065 0.3048)
			(stroke
				(width 0.1)
				(type default)
			)
			(layer "B.Fab")
		)
		(fp_line
			(start 0.12065 0.3048)
			(end 0.67945 0.3048)
			(stroke
				(width 0.1)
				(type default)
			)
			(layer "B.Fab")
		)
		(fp_line
			(start 0.67945 -0.305054)
			(end 0.12065 -0.305054)
			(stroke
				(width 0.1)
				(type default)
			)
			(layer "B.Fab")
		)
		(fp_line
			(start 0.67945 0.3048)
			(end 0.67945 -0.305054)
			(stroke
				(width 0.1)
				(type default)
			)
			(layer "B.Fab")
		)
		(pad "1" smd circle
			(at 0.40005 0 180)
			(size 0 0)
			(layers "B.Cu" "B.Mask" "B.Paste")
			(net "PVDD18_S5_P1")
		)
		(pad "2" smd circle
			(at -0.40005 0 180)
			(size 0 0)
			(layers "B.Cu" "B.Mask" "B.Paste")
			(net "CPU1_NMI_SYNC_FLOOD_N")
		)
	)
	(footprint ""
		(layer "B.Cu")
		(at 138.24204 -389.81126)
		(property "Reference" "PJ09_P1_P"
			(at 0 0 0)
			(layer "B.SilkS")
			(hide yes)
			(effects
				(font
					(size 1.27 1.27)
				)
				(justify mirror)
			)
		)
		(property "Value" ""
			(at 0 0 0)
			(layer "B.Fab")
			(effects
				(font
					(size 1.27 1.27)
				)
				(justify mirror)
			)
		)
		(duplicate_pad_numbers_are_jumpers no)
		(zone
			(layer "In15.Cu")
			(hatch none 0.5)
			(connect_pads
				(clearance 0)
			)
			(min_thickness 0.25)
			(keepout
				(tracks allowed)
				(vias not_allowed)
				(pads allowed)
				(copperpour not_allowed)
				(footprints allowed)
			)
			(placement
				(enabled no)
				(sheetname "")
			)
			(fill
				(thermal_gap 0.5)
				(thermal_bridge_width 0.5)
				(island_removal_mode 0)
			)
			(polygon
				(pts
					(xy 138.45794 -389.62076) (xy 138.02614 -389.62076) (xy 138.02614 -390.00176) (xy 138.45794 -390.00176)
				)
			)
		)
	)
	(footprint ""
		(layer "B.Cu")
		(at 111.11738 -175.506634 90)
		(property "Reference" "PR200"
			(at 0 0 90)
			(layer "B.SilkS")
			(hide yes)
			(effects
				(font
					(size 1.27 1.27)
				)
				(justify mirror)
			)
		)
		(property "Value" ""
			(at 0 0 90)
			(layer "B.Fab")
			(effects
				(font
					(size 1.27 1.27)
				)
				(justify mirror)
			)
		)
		(duplicate_pad_numbers_are_jumpers no)
		(fp_line
			(start 0.7874 -0.4064)
			(end -0.7874 -0.4064)
			(stroke
				(width 0.1524)
				(type default)
			)
			(layer "B.SilkS")
		)
		(fp_line
			(start -0.7874 -0.4064)
			(end -0.7874 0.4064)
			(stroke
				(width 0.1524)
				(type default)
			)
			(layer "B.SilkS")
		)
		(fp_line
			(start 0.7874 0.4064)
			(end 0.7874 -0.4064)
			(stroke
				(width 0.1524)
				(type default)
			)
			(layer "B.SilkS")
		)
		(fp_line
			(start -0.7874 0.4064)
			(end 0.7874 0.4064)
			(stroke
				(width 0.1524)
				(type default)
			)
			(layer "B.SilkS")
		)
		(fp_line
			(start 0.67945 -0.305054)
			(end 0.12065 -0.305054)
			(stroke
				(width 0.1)
				(type default)
			)
			(layer "B.Fab")
		)
		(fp_line
			(start 0.12065 -0.305054)
			(end 0.12065 -0.2794)
			(stroke
				(width 0.1)
				(type default)
			)
			(layer "B.Fab")
		)
		(fp_line
			(start -0.12065 -0.3048)
			(end -0.67945 -0.3048)
			(stroke
				(width 0.1)
				(type default)
			)
			(layer "B.Fab")
		)
		(fp_line
			(start -0.67945 -0.3048)
			(end -0.67945 0.3048)
			(stroke
				(width 0.1)
				(type default)
			)
			(layer "B.Fab")
		)
		(fp_line
			(start 0.12065 -0.2794)
			(end -0.12065 -0.2794)
			(stroke
				(width 0.1)
				(type default)
			)
			(layer "B.Fab")
		)
		(fp_line
			(start -0.12065 -0.2794)
			(end -0.12065 -0.3048)
			(stroke
				(width 0.1)
				(type default)
			)
			(layer "B.Fab")
		)
		(fp_line
			(start 0.12065 0.2794)
			(end 0.12065 0.3048)
			(stroke
				(width 0.1)
				(type default)
			)
			(layer "B.Fab")
		)
		(fp_line
			(start -0.120396 0.2794)
			(end 0.12065 0.2794)
			(stroke
				(width 0.1)
				(type default)
			)
			(layer "B.Fab")
		)
		(fp_line
			(start 0.67945 0.3048)
			(end 0.67945 -0.305054)
			(stroke
				(width 0.1)
				(type default)
			)
			(layer "B.Fab")
		)
		(fp_line
			(start 0.12065 0.3048)
			(end 0.67945 0.3048)
			(stroke
				(width 0.1)
				(type default)
			)
			(layer "B.Fab")
		)
		(fp_line
			(start -0.120396 0.3048)
			(end -0.120396 0.2794)
			(stroke
				(width 0.1)
				(type default)
			)
			(layer "B.Fab")
		)
		(fp_line
			(start -0.67945 0.3048)
			(end -0.120396 0.3048)
			(stroke
				(width 0.1)
				(type default)
			)
			(layer "B.Fab")
		)
		(pad "1" smd circle
			(at 0.40005 0 270)
			(size 0 0)
			(layers "B.Cu" "B.Mask" "B.Paste")
			(net "PVDDCR_CPU0_P1_VOS4")
		)
		(pad "2" smd circle
			(at -0.40005 0 270)
			(size 0 0)
			(layers "B.Cu" "B.Mask" "B.Paste")
			(net "PVDDCR_CPU0_P1")
		)
	)
	(footprint ""
		(layer "B.Cu")
		(at 135.694166 -408.517344 90)
		(property "Reference" "C6737"
			(at 0 0 90)
			(layer "B.SilkS")
			(hide yes)
			(effects
				(font
					(size 1.27 1.27)
				)
				(justify mirror)
			)
		)
		(property "Value" ""
			(at 0 0 90)
			(layer "B.Fab")
			(effects
				(font
					(size 1.27 1.27)
				)
				(justify mirror)
			)
		)
		(duplicate_pad_numbers_are_jumpers no)
		(fp_line
			(start 0.299974 -0.150114)
			(end -0.299974 -0.150114)
			(stroke
				(width 0.1)
				(type default)
			)
			(layer "B.Fab")
		)
		(fp_line
			(start -0.299974 -0.150114)
			(end -0.299974 0.150114)
			(stroke
				(width 0.1)
				(type default)
			)
			(layer "B.Fab")
		)
		(fp_line
			(start 0.299974 0.150114)
			(end 0.299974 -0.150114)
			(stroke
				(width 0.1)
				(type default)
			)
			(layer "B.Fab")
		)
		(fp_line
			(start -0.299974 0.150114)
			(end 0.299974 0.150114)
			(stroke
				(width 0.1)
				(type default)
			)
			(layer "B.Fab")
		)
		(pad "1" smd rect
			(at 0.2667 0 270)
			(size 0.3048 0.381)
			(layers "B.Cu" "B.Mask" "B.Paste")
			(net "P5E_CPU1_P3_TX_BUF_C_DP<6>")
		)
		(pad "2" smd rect
			(at -0.2667 0 270)
			(size 0.3048 0.381)
			(layers "B.Cu" "B.Mask" "B.Paste")
			(net "P5E_CPU1_P3_TX_BUF_DP<6>")
		)
	)
	(footprint ""
		(layer "B.Cu")
		(at 339.134958 -305.812952)
		(property "Reference" "R2318"
			(at 0 0 0)
			(layer "B.SilkS")
			(hide yes)
			(effects
				(font
					(size 1.27 1.27)
				)
				(justify mirror)
			)
		)
		(property "Value" ""
			(at 0 0 0)
			(layer "B.Fab")
			(effects
				(font
					(size 1.27 1.27)
				)
				(justify mirror)
			)
		)
		(duplicate_pad_numbers_are_jumpers no)
		(fp_line
			(start -0.7874 -0.4064)
			(end -0.7874 0.4064)
			(stroke
				(width 0.1524)
				(type default)
			)
			(layer "B.SilkS")
		)
		(fp_line
			(start -0.7874 0.4064)
			(end 0.7874 0.4064)
			(stroke
				(width 0.1524)
				(type default)
			)
			(layer "B.SilkS")
		)
		(fp_line
			(start 0.7874 -0.4064)
			(end -0.7874 -0.4064)
			(stroke
				(width 0.1524)
				(type default)
			)
			(layer "B.SilkS")
		)
		(fp_line
			(start 0.7874 0.4064)
			(end 0.7874 -0.4064)
			(stroke
				(width 0.1524)
				(type default)
			)
			(layer "B.SilkS")
		)
		(fp_line
			(start -0.67945 -0.3048)
			(end -0.67945 0.3048)
			(stroke
				(width 0.1)
				(type default)
			)
			(layer "B.Fab")
		)
		(fp_line
			(start -0.67945 0.3048)
			(end -0.120396 0.3048)
			(stroke
				(width 0.1)
				(type default)
			)
			(layer "B.Fab")
		)
		(fp_line
			(start -0.12065 -0.3048)
			(end -0.67945 -0.3048)
			(stroke
				(width 0.1)
				(type default)
			)
			(layer "B.Fab")
		)
		(fp_line
			(start -0.12065 -0.2794)
			(end -0.12065 -0.3048)
			(stroke
				(width 0.1)
				(type default)
			)
			(layer "B.Fab")
		)
		(fp_line
			(start -0.120396 0.2794)
			(end 0.12065 0.2794)
			(stroke
				(width 0.1)
				(type default)
			)
			(layer "B.Fab")
		)
		(fp_line
			(start -0.120396 0.3048)
			(end -0.120396 0.2794)
			(stroke
				(width 0.1)
				(type default)
			)
			(layer "B.Fab")
		)
		(fp_line
			(start 0.12065 -0.305054)
			(end 0.12065 -0.2794)
			(stroke
				(width 0.1)
				(type default)
			)
			(layer "B.Fab")
		)
		(fp_line
			(start 0.12065 -0.2794)
			(end -0.12065 -0.2794)
			(stroke
				(width 0.1)
				(type default)
			)
			(layer "B.Fab")
		)
		(fp_line
			(start 0.12065 0.2794)
			(end 0.12065 0.3048)
			(stroke
				(width 0.1)
				(type default)
			)
			(layer "B.Fab")
		)
		(fp_line
			(start 0.12065 0.3048)
			(end 0.67945 0.3048)
			(stroke
				(width 0.1)
				(type default)
			)
			(layer "B.Fab")
		)
		(fp_line
			(start 0.67945 -0.305054)
			(end 0.12065 -0.305054)
			(stroke
				(width 0.1)
				(type default)
			)
			(layer "B.Fab")
		)
		(fp_line
			(start 0.67945 0.3048)
			(end 0.67945 -0.305054)
			(stroke
				(width 0.1)
				(type default)
			)
			(layer "B.Fab")
		)
		(pad "1" smd circle
			(at 0.40005 0 180)
			(size 0 0)
			(layers "B.Cu" "B.Mask" "B.Paste")
			(net "UART_CPU0_SCM_UART1_R_TX")
		)
		(pad "2" smd circle
			(at -0.40005 0 180)
			(size 0 0)
			(layers "B.Cu" "B.Mask" "B.Paste")
			(net "UART_CPU0_SCM_UART1_TX")
		)
	)
	(footprint ""
		(layer "B.Cu")
		(at 369.646454 -255.84531)
		(property "Reference" "C2130"
			(at 0 0 0)
			(layer "B.SilkS")
			(hide yes)
			(effects
				(font
					(size 1.27 1.27)
				)
				(justify mirror)
			)
		)
		(property "Value" ""
			(at 0 0 0)
			(layer "B.Fab")
			(effects
				(font
					(size 1.27 1.27)
				)
				(justify mirror)
			)
		)
		(duplicate_pad_numbers_are_jumpers no)
		(fp_line
			(start -0.7874 -0.4064)
			(end -0.7874 0.4064)
			(stroke
				(width 0.1524)
				(type default)
			)
			(layer "B.SilkS")
		)
		(fp_line
			(start -0.7874 0.4064)
			(end 0.7874 0.4064)
			(stroke
				(width 0.1524)
				(type default)
			)
			(layer "B.SilkS")
		)
		(fp_line
			(start 0.7874 -0.4064)
			(end -0.7874 -0.4064)
			(stroke
				(width 0.1524)
				(type default)
			)
			(layer "B.SilkS")
		)
		(fp_line
			(start 0.7874 0.4064)
			(end 0.7874 -0.4064)
			(stroke
				(width 0.1524)
				(type default)
			)
			(layer "B.SilkS")
		)
		(fp_line
			(start -0.67945 -0.3048)
			(end -0.67945 0.3048)
			(stroke
				(width 0.1)
				(type default)
			)
			(layer "B.Fab")
		)
		(fp_line
			(start -0.67945 0.3048)
			(end -0.120396 0.3048)
			(stroke
				(width 0.1)
				(type default)
			)
			(layer "B.Fab")
		)
		(fp_line
			(start -0.12065 -0.3048)
			(end -0.67945 -0.3048)
			(stroke
				(width 0.1)
				(type default)
			)
			(layer "B.Fab")
		)
		(fp_line
			(start -0.12065 -0.2794)
			(end -0.12065 -0.3048)
			(stroke
				(width 0.1)
				(type default)
			)
			(layer "B.Fab")
		)
		(fp_line
			(start -0.120396 0.2794)
			(end 0.12065 0.2794)
			(stroke
				(width 0.1)
				(type default)
			)
			(layer "B.Fab")
		)
		(fp_line
			(start -0.120396 0.3048)
			(end -0.120396 0.2794)
			(stroke
				(width 0.1)
				(type default)
			)
			(layer "B.Fab")
		)
		(fp_line
			(start 0.12065 -0.305054)
			(end 0.12065 -0.2794)
			(stroke
				(width 0.1)
				(type default)
			)
			(layer "B.Fab")
		)
		(fp_line
			(start 0.12065 -0.2794)
			(end -0.12065 -0.2794)
			(stroke
				(width 0.1)
				(type default)
			)
			(layer "B.Fab")
		)
		(fp_line
			(start 0.12065 0.2794)
			(end 0.12065 0.3048)
			(stroke
				(width 0.1)
				(type default)
			)
			(layer "B.Fab")
		)
		(fp_line
			(start 0.12065 0.3048)
			(end 0.67945 0.3048)
			(stroke
				(width 0.1)
				(type default)
			)
			(layer "B.Fab")
		)
		(fp_line
			(start 0.67945 -0.305054)
			(end 0.12065 -0.305054)
			(stroke
				(width 0.1)
				(type default)
			)
			(layer "B.Fab")
		)
		(fp_line
			(start 0.67945 0.3048)
			(end 0.67945 -0.305054)
			(stroke
				(width 0.1)
				(type default)
			)
			(layer "B.Fab")
		)
		(pad "1" smd circle
			(at 0.40005 0 180)
			(size 0 0)
			(layers "B.Cu" "B.Mask" "B.Paste")
			(net "PVDDCR_SOC_P0")
		)
		(pad "2" smd circle
			(at -0.40005 0 180)
			(size 0 0)
			(layers "B.Cu" "B.Mask" "B.Paste")
			(net "GND")
		)
	)
	(footprint ""
		(layer "B.Cu")
		(at 457.347066 -397.05407 90)
		(property "Reference" "PC6580_2"
			(at 0 0 90)
			(layer "B.SilkS")
			(hide yes)
			(effects
				(font
					(size 1.27 1.27)
				)
				(justify mirror)
			)
		)
		(property "Value" ""
			(at 0 0 90)
			(layer "B.Fab")
			(effects
				(font
					(size 1.27 1.27)
				)
				(justify mirror)
			)
		)
		(duplicate_pad_numbers_are_jumpers no)
		(fp_line
			(start 1.524 -0.762)
			(end -1.524 -0.762)
			(stroke
				(width 0.1524)
				(type default)
			)
			(layer "B.SilkS")
		)
		(fp_line
			(start -1.524 -0.762)
			(end -1.524 0.762)
			(stroke
				(width 0.1524)
				(type default)
			)
			(layer "B.SilkS")
		)
		(fp_line
			(start 1.524 0.762)
			(end 1.524 -0.762)
			(stroke
				(width 0.1524)
				(type default)
			)
			(layer "B.SilkS")
		)
		(fp_line
			(start -1.524 0.762)
			(end 1.524 0.762)
			(stroke
				(width 0.1524)
				(type default)
			)
			(layer "B.SilkS")
		)
		(fp_line
			(start 1.1049 -0.724916)
			(end 1.1049 0.724916)
			(stroke
				(width 0.1)
				(type default)
			)
			(layer "B.Fab")
		)
		(fp_line
			(start -1.1049 -0.724916)
			(end 1.1049 -0.724916)
			(stroke
				(width 0.1)
				(type default)
			)
			(layer "B.Fab")
		)
		(fp_line
			(start 1.1049 0.724916)
			(end -1.1049 0.724916)
			(stroke
				(width 0.1)
				(type default)
			)
			(layer "B.Fab")
		)
		(fp_line
			(start -1.1049 0.724916)
			(end -1.1049 -0.724916)
			(stroke
				(width 0.1)
				(type default)
			)
			(layer "B.Fab")
		)
		(pad "1" smd rect
			(at 0.889 0 90)
			(size 1.016 1.27)
			(layers "B.Cu" "B.Mask" "B.Paste")
			(net "SW_P12V_AUX_P0V9_RETIMER_CPU0_FLT")
		)
		(pad "2" smd rect
			(at -0.889 0 90)
			(size 1.016 1.27)
			(layers "B.Cu" "B.Mask" "B.Paste")
			(net "GND")
		)
	)
	(footprint ""
		(layer "B.Cu")
		(at 186.806078 -97.085912 -90)
		(property "Reference" "R180"
			(at 0 0 90)
			(layer "B.SilkS")
			(hide yes)
			(effects
				(font
					(size 1.27 1.27)
				)
				(justify mirror)
			)
		)
		(property "Value" ""
			(at 0 0 90)
			(layer "B.Fab")
			(effects
				(font
					(size 1.27 1.27)
				)
				(justify mirror)
			)
		)
		(duplicate_pad_numbers_are_jumpers no)
		(fp_line
			(start -0.7874 0.4064)
			(end 0.7874 0.4064)
			(stroke
				(width 0.1524)
				(type default)
			)
			(layer "B.SilkS")
		)
		(fp_line
			(start 0.7874 0.4064)
			(end 0.7874 -0.4064)
			(stroke
				(width 0.1524)
				(type default)
			)
			(layer "B.SilkS")
		)
		(fp_line
			(start -0.7874 -0.4064)
			(end -0.7874 0.4064)
			(stroke
				(width 0.1524)
				(type default)
			)
			(layer "B.SilkS")
		)
		(fp_line
			(start 0.7874 -0.4064)
			(end -0.7874 -0.4064)
			(stroke
				(width 0.1524)
				(type default)
			)
			(layer "B.SilkS")
		)
		(fp_line
			(start -0.67945 0.3048)
			(end -0.120396 0.3048)
			(stroke
				(width 0.1)
				(type default)
			)
			(layer "B.Fab")
		)
		(fp_line
			(start -0.120396 0.3048)
			(end -0.120396 0.2794)
			(stroke
				(width 0.1)
				(type default)
			)
			(layer "B.Fab")
		)
		(fp_line
			(start 0.12065 0.3048)
			(end 0.67945 0.3048)
			(stroke
				(width 0.1)
				(type default)
			)
			(layer "B.Fab")
		)
		(fp_line
			(start 0.67945 0.3048)
			(end 0.67945 -0.305054)
			(stroke
				(width 0.1)
				(type default)
			)
			(layer "B.Fab")
		)
		(fp_line
			(start -0.120396 0.2794)
			(end 0.12065 0.2794)
			(stroke
				(width 0.1)
				(type default)
			)
			(layer "B.Fab")
		)
		(fp_line
			(start 0.12065 0.2794)
			(end 0.12065 0.3048)
			(stroke
				(width 0.1)
				(type default)
			)
			(layer "B.Fab")
		)
		(fp_line
			(start -0.12065 -0.2794)
			(end -0.12065 -0.3048)
			(stroke
				(width 0.1)
				(type default)
			)
			(layer "B.Fab")
		)
		(fp_line
			(start 0.12065 -0.2794)
			(end -0.12065 -0.2794)
			(stroke
				(width 0.1)
				(type default)
			)
			(layer "B.Fab")
		)
		(fp_line
			(start -0.67945 -0.3048)
			(end -0.67945 0.3048)
			(stroke
				(width 0.1)
				(type default)
			)
			(layer "B.Fab")
		)
		(fp_line
			(start -0.12065 -0.3048)
			(end -0.67945 -0.3048)
			(stroke
				(width 0.1)
				(type default)
			)
			(layer "B.Fab")
		)
		(fp_line
			(start 0.12065 -0.305054)
			(end 0.12065 -0.2794)
			(stroke
				(width 0.1)
				(type default)
			)
			(layer "B.Fab")
		)
		(fp_line
			(start 0.67945 -0.305054)
			(end 0.12065 -0.305054)
			(stroke
				(width 0.1)
				(type default)
			)
			(layer "B.Fab")
		)
		(pad "1" smd circle
			(at 0.40005 0 90)
			(size 0 0)
			(layers "B.Cu" "B.Mask" "B.Paste")
			(net "CPU0_SP5R1")
		)
		(pad "2" smd circle
			(at -0.40005 0 90)
			(size 0 0)
			(layers "B.Cu" "B.Mask" "B.Paste")
			(net "FM_CPU0_SP5R1")
		)
	)
)
